(kicad_pcb
	(version 20260206)
	(generator "pcbnew")
	(generator_version "10.0")
	(general
		(thickness 1.6)
		(legacy_teardrops no)
	)
	(paper "A4")
	(title_block
		(title "04192023_DAF0TMB3IC0_F0TG_MB_C_brd_V02_OCP.brd")
		(comment 1 "Grand Teton / footprints 3461-3468 of 8354")
	)
	(layers
		(0 "F.Cu" signal "TOP")
		(4 "In1.Cu" signal "GND")
		(6 "In2.Cu" signal "IN1")
		(8 "In3.Cu" signal "GND1")
		(10 "In4.Cu" signal "IN2")
		(12 "In5.Cu" signal "GND2")
		(14 "In6.Cu" signal "IN3")
		(16 "In7.Cu" signal "GND3")
		(18 "In8.Cu" signal "VCC")
		(20 "In9.Cu" signal "VCC1")
		(22 "In10.Cu" signal "GND4")
		(24 "In11.Cu" signal "IN4")
		(26 "In12.Cu" signal "GND5")
		(28 "In13.Cu" signal "IN5")
		(30 "In14.Cu" signal "GND6")
		(32 "In15.Cu" signal "IN6")
		(34 "In16.Cu" signal "GND7")
		(2 "B.Cu" signal "BOTTOM")
		(9 "F.Adhes" user "F.Adhesive")
		(11 "B.Adhes" user "B.Adhesive")
		(13 "F.Paste" user "Package Geometry/Pastemask Top")
		(15 "B.Paste" user "Package Geometry/Pastemask Bottom")
		(5 "F.SilkS" user "Ref Des/Silkscreen Top")
		(7 "B.SilkS" user "Ref Des/Silkscreen Bottom")
		(1 "F.Mask" user "Board Geometry/Soldermask Top")
		(3 "B.Mask" user "Board Geometry/Soldermask Bottom")
		(17 "Dwgs.User" user "User.Drawings")
		(19 "Cmts.User" user "User.Comments")
		(21 "Eco1.User" user "User.Eco1")
		(23 "Eco2.User" user "User.Eco2")
		(25 "Edge.Cuts" user "Board Geometry/Outline")
		(27 "Margin" user)
		(31 "F.CrtYd" user "Package Geometry/Place Bound Top")
		(29 "B.CrtYd" user "Package Geometry/Place Bound Bottom")
		(35 "F.Fab" user "Ref Des/Assembly Top")
		(33 "B.Fab" user "Ref Des/Assembly Bottom")
	)
	(footprint ""
		(layer "F.Cu")
		(at 348.972124 -344.792046 90)
		(property "Reference" "PC111_6"
			(at 0 0 90)
			(layer "F.SilkS")
			(hide yes)
			(effects
				(font
					(size 1.27 1.27)
				)
			)
		)
		(property "Value" ""
			(at 0 0 90)
			(layer "F.Fab")
			(effects
				(font
					(size 1.27 1.27)
				)
			)
		)
		(duplicate_pad_numbers_are_jumpers no)
		(fp_line
			(start 0.7874 -0.4064)
			(end 0.7874 0.4064)
			(stroke
				(width 0.1524)
				(type default)
			)
			(layer "F.SilkS")
		)
		(fp_line
			(start -0.7874 -0.4064)
			(end 0.7874 -0.4064)
			(stroke
				(width 0.1524)
				(type default)
			)
			(layer "F.SilkS")
		)
		(fp_line
			(start 0.7874 0.4064)
			(end -0.7874 0.4064)
			(stroke
				(width 0.1524)
				(type default)
			)
			(layer "F.SilkS")
		)
		(fp_line
			(start -0.7874 0.4064)
			(end -0.7874 -0.4064)
			(stroke
				(width 0.1524)
				(type default)
			)
			(layer "F.SilkS")
		)
		(fp_line
			(start -0.12065 -0.305054)
			(end -0.12065 -0.2794)
			(stroke
				(width 0.1)
				(type default)
			)
			(layer "F.Fab")
		)
		(fp_line
			(start -0.67945 -0.305054)
			(end -0.12065 -0.305054)
			(stroke
				(width 0.1)
				(type default)
			)
			(layer "F.Fab")
		)
		(fp_line
			(start 0.67945 -0.3048)
			(end 0.67945 0.3048)
			(stroke
				(width 0.1)
				(type default)
			)
			(layer "F.Fab")
		)
		(fp_line
			(start 0.12065 -0.3048)
			(end 0.67945 -0.3048)
			(stroke
				(width 0.1)
				(type default)
			)
			(layer "F.Fab")
		)
		(fp_line
			(start 0.12065 -0.2794)
			(end 0.12065 -0.3048)
			(stroke
				(width 0.1)
				(type default)
			)
			(layer "F.Fab")
		)
		(fp_line
			(start -0.12065 -0.2794)
			(end 0.12065 -0.2794)
			(stroke
				(width 0.1)
				(type default)
			)
			(layer "F.Fab")
		)
		(fp_line
			(start 0.120396 0.2794)
			(end -0.12065 0.2794)
			(stroke
				(width 0.1)
				(type default)
			)
			(layer "F.Fab")
		)
		(fp_line
			(start -0.12065 0.2794)
			(end -0.12065 0.3048)
			(stroke
				(width 0.1)
				(type default)
			)
			(layer "F.Fab")
		)
		(fp_line
			(start 0.67945 0.3048)
			(end 0.120396 0.3048)
			(stroke
				(width 0.1)
				(type default)
			)
			(layer "F.Fab")
		)
		(fp_line
			(start 0.120396 0.3048)
			(end 0.120396 0.2794)
			(stroke
				(width 0.1)
				(type default)
			)
			(layer "F.Fab")
		)
		(fp_line
			(start -0.12065 0.3048)
			(end -0.67945 0.3048)
			(stroke
				(width 0.1)
				(type default)
			)
			(layer "F.Fab")
		)
		(fp_line
			(start -0.67945 0.3048)
			(end -0.67945 -0.305054)
			(stroke
				(width 0.1)
				(type default)
			)
			(layer "F.Fab")
		)
		(pad "1" smd circle
			(at -0.40005 0 90)
			(size 0 0)
			(layers "F.Cu" "F.Mask" "F.Paste")
			(net "PVDDCR_CPU1_P0_VCCS")
		)
		(pad "2" smd circle
			(at 0.40005 0 90)
			(size 0 0)
			(layers "F.Cu" "F.Mask" "F.Paste")
			(net "GND")
		)
	)
	(footprint ""
		(layer "F.Cu")
		(at 66.929 -55.245 180)
		(property "Reference" "R1179"
			(at 0 0 180)
			(layer "F.SilkS")
			(hide yes)
			(effects
				(font
					(size 1.27 1.27)
				)
			)
		)
		(property "Value" ""
			(at 0 0 180)
			(layer "F.Fab")
			(effects
				(font
					(size 1.27 1.27)
				)
			)
		)
		(duplicate_pad_numbers_are_jumpers no)
		(fp_line
			(start 0.7874 0.4064)
			(end -0.7874 0.4064)
			(stroke
				(width 0.1524)
				(type default)
			)
			(layer "F.SilkS")
		)
		(fp_line
			(start 0.7874 -0.4064)
			(end 0.7874 0.4064)
			(stroke
				(width 0.1524)
				(type default)
			)
			(layer "F.SilkS")
		)
		(fp_line
			(start -0.7874 0.4064)
			(end -0.7874 -0.4064)
			(stroke
				(width 0.1524)
				(type default)
			)
			(layer "F.SilkS")
		)
		(fp_line
			(start -0.7874 -0.4064)
			(end 0.7874 -0.4064)
			(stroke
				(width 0.1524)
				(type default)
			)
			(layer "F.SilkS")
		)
		(fp_line
			(start 0.67945 0.3048)
			(end 0.120396 0.3048)
			(stroke
				(width 0.1)
				(type default)
			)
			(layer "F.Fab")
		)
		(fp_line
			(start 0.67945 -0.3048)
			(end 0.67945 0.3048)
			(stroke
				(width 0.1)
				(type default)
			)
			(layer "F.Fab")
		)
		(fp_line
			(start 0.12065 -0.2794)
			(end 0.12065 -0.3048)
			(stroke
				(width 0.1)
				(type default)
			)
			(layer "F.Fab")
		)
		(fp_line
			(start 0.12065 -0.3048)
			(end 0.67945 -0.3048)
			(stroke
				(width 0.1)
				(type default)
			)
			(layer "F.Fab")
		)
		(fp_line
			(start 0.120396 0.3048)
			(end 0.120396 0.2794)
			(stroke
				(width 0.1)
				(type default)
			)
			(layer "F.Fab")
		)
		(fp_line
			(start 0.120396 0.2794)
			(end -0.12065 0.2794)
			(stroke
				(width 0.1)
				(type default)
			)
			(layer "F.Fab")
		)
		(fp_line
			(start -0.12065 0.3048)
			(end -0.67945 0.3048)
			(stroke
				(width 0.1)
				(type default)
			)
			(layer "F.Fab")
		)
		(fp_line
			(start -0.12065 0.2794)
			(end -0.12065 0.3048)
			(stroke
				(width 0.1)
				(type default)
			)
			(layer "F.Fab")
		)
		(fp_line
			(start -0.12065 -0.2794)
			(end 0.12065 -0.2794)
			(stroke
				(width 0.1)
				(type default)
			)
			(layer "F.Fab")
		)
		(fp_line
			(start -0.12065 -0.305054)
			(end -0.12065 -0.2794)
			(stroke
				(width 0.1)
				(type default)
			)
			(layer "F.Fab")
		)
		(fp_line
			(start -0.67945 0.3048)
			(end -0.67945 -0.305054)
			(stroke
				(width 0.1)
				(type default)
			)
			(layer "F.Fab")
		)
		(fp_line
			(start -0.67945 -0.305054)
			(end -0.12065 -0.305054)
			(stroke
				(width 0.1)
				(type default)
			)
			(layer "F.Fab")
		)
		(pad "1" smd circle
			(at -0.40005 0 180)
			(size 0 0)
			(layers "F.Cu" "F.Mask" "F.Paste")
			(net "FM_OCP_V3_2_AUX_PWR_R_EN")
		)
		(pad "2" smd circle
			(at 0.40005 0 180)
			(size 0 0)
			(layers "F.Cu" "F.Mask" "F.Paste")
			(net "FM_OCP_V3_2_AUX_PWR_EN")
		)
	)
	(footprint ""
		(layer "F.Cu")
		(at 402.214842 -404.873206 -90)
		(property "Reference" "R1066"
			(at 0 0 270)
			(layer "F.SilkS")
			(hide yes)
			(effects
				(font
					(size 1.27 1.27)
				)
			)
		)
		(property "Value" ""
			(at 0 0 270)
			(layer "F.Fab")
			(effects
				(font
					(size 1.27 1.27)
				)
			)
		)
		(duplicate_pad_numbers_are_jumpers no)
		(fp_line
			(start -0.32512 0.175006)
			(end -0.32512 -0.175006)
			(stroke
				(width 0.1)
				(type default)
			)
			(layer "F.Fab")
		)
		(fp_line
			(start 0.32512 0.175006)
			(end -0.32512 0.175006)
			(stroke
				(width 0.1)
				(type default)
			)
			(layer "F.Fab")
		)
		(fp_line
			(start -0.32512 -0.175006)
			(end 0.32512 -0.175006)
			(stroke
				(width 0.1)
				(type default)
			)
			(layer "F.Fab")
		)
		(fp_line
			(start 0.32512 -0.175006)
			(end 0.32512 0.175006)
			(stroke
				(width 0.1)
				(type default)
			)
			(layer "F.Fab")
		)
		(pad "1" smd rect
			(at -0.2667 0 270)
			(size 0.3048 0.381)
			(layers "F.Cu" "F.Mask" "F.Paste")
			(net "P1V8_CPU0_RT_1D")
		)
		(pad "2" smd rect
			(at 0.2667 0 90)
			(size 0.3048 0.381)
			(layers "F.Cu" "F.Mask" "F.Paste")
			(net "JTAG_TEST_MODE_RT_CPU0_P2")
		)
	)
	(footprint ""
		(layer "F.Cu")
		(at 45.932344 -419.700964)
		(property "Reference" "R1466"
			(at 0 0 0)
			(layer "F.SilkS")
			(hide yes)
			(effects
				(font
					(size 1.27 1.27)
				)
			)
		)
		(property "Value" ""
			(at 0 0 0)
			(layer "F.Fab")
			(effects
				(font
					(size 1.27 1.27)
				)
			)
		)
		(duplicate_pad_numbers_are_jumpers no)
		(fp_line
			(start -0.32512 -0.175006)
			(end 0.32512 -0.175006)
			(stroke
				(width 0.1)
				(type default)
			)
			(layer "F.Fab")
		)
		(fp_line
			(start -0.32512 0.175006)
			(end -0.32512 -0.175006)
			(stroke
				(width 0.1)
				(type default)
			)
			(layer "F.Fab")
		)
		(fp_line
			(start 0.32512 -0.175006)
			(end 0.32512 0.175006)
			(stroke
				(width 0.1)
				(type default)
			)
			(layer "F.Fab")
		)
		(fp_line
			(start 0.32512 0.175006)
			(end -0.32512 0.175006)
			(stroke
				(width 0.1)
				(type default)
			)
			(layer "F.Fab")
		)
		(pad "1" smd rect
			(at -0.2667 0)
			(size 0.3048 0.381)
			(layers "F.Cu" "F.Mask" "F.Paste")
			(net "P1V8_CPU1_RT_1D")
		)
		(pad "2" smd rect
			(at 0.2667 0 180)
			(size 0.3048 0.381)
			(layers "F.Cu" "F.Mask" "F.Paste")
			(net "JTAG_TDO_RT_CPU1_P0")
		)
	)
	(footprint ""
		(layer "F.Cu")
		(at 53.866542 -360.473498)
		(property "Reference" "PC438"
			(at 0 0 0)
			(layer "F.SilkS")
			(hide yes)
			(effects
				(font
					(size 1.27 1.27)
				)
			)
		)
		(property "Value" ""
			(at 0 0 0)
			(layer "F.Fab")
			(effects
				(font
					(size 1.27 1.27)
				)
			)
		)
		(duplicate_pad_numbers_are_jumpers no)
		(fp_line
			(start -0.7874 -0.4064)
			(end 0.7874 -0.4064)
			(stroke
				(width 0.1524)
				(type default)
			)
			(layer "F.SilkS")
		)
		(fp_line
			(start -0.7874 0.4064)
			(end -0.7874 -0.4064)
			(stroke
				(width 0.1524)
				(type default)
			)
			(layer "F.SilkS")
		)
		(fp_line
			(start 0.7874 -0.4064)
			(end 0.7874 0.4064)
			(stroke
				(width 0.1524)
				(type default)
			)
			(layer "F.SilkS")
		)
		(fp_line
			(start 0.7874 0.4064)
			(end -0.7874 0.4064)
			(stroke
				(width 0.1524)
				(type default)
			)
			(layer "F.SilkS")
		)
		(fp_line
			(start -0.67945 -0.305054)
			(end -0.12065 -0.305054)
			(stroke
				(width 0.1)
				(type default)
			)
			(layer "F.Fab")
		)
		(fp_line
			(start -0.67945 0.3048)
			(end -0.67945 -0.305054)
			(stroke
				(width 0.1)
				(type default)
			)
			(layer "F.Fab")
		)
		(fp_line
			(start -0.12065 -0.305054)
			(end -0.12065 -0.2794)
			(stroke
				(width 0.1)
				(type default)
			)
			(layer "F.Fab")
		)
		(fp_line
			(start -0.12065 -0.2794)
			(end 0.12065 -0.2794)
			(stroke
				(width 0.1)
				(type default)
			)
			(layer "F.Fab")
		)
		(fp_line
			(start -0.12065 0.2794)
			(end -0.12065 0.3048)
			(stroke
				(width 0.1)
				(type default)
			)
			(layer "F.Fab")
		)
		(fp_line
			(start -0.12065 0.3048)
			(end -0.67945 0.3048)
			(stroke
				(width 0.1)
				(type default)
			)
			(layer "F.Fab")
		)
		(fp_line
			(start 0.120396 0.2794)
			(end -0.12065 0.2794)
			(stroke
				(width 0.1)
				(type default)
			)
			(layer "F.Fab")
		)
		(fp_line
			(start 0.120396 0.3048)
			(end 0.120396 0.2794)
			(stroke
				(width 0.1)
				(type default)
			)
			(layer "F.Fab")
		)
		(fp_line
			(start 0.12065 -0.3048)
			(end 0.67945 -0.3048)
			(stroke
				(width 0.1)
				(type default)
			)
			(layer "F.Fab")
		)
		(fp_line
			(start 0.12065 -0.2794)
			(end 0.12065 -0.3048)
			(stroke
				(width 0.1)
				(type default)
			)
			(layer "F.Fab")
		)
		(fp_line
			(start 0.67945 -0.3048)
			(end 0.67945 0.3048)
			(stroke
				(width 0.1)
				(type default)
			)
			(layer "F.Fab")
		)
		(fp_line
			(start 0.67945 0.3048)
			(end 0.120396 0.3048)
			(stroke
				(width 0.1)
				(type default)
			)
			(layer "F.Fab")
		)
		(pad "1" smd circle
			(at -0.40005 0)
			(size 0 0)
			(layers "F.Cu" "F.Mask" "F.Paste")
			(net "P12V_AUX")
		)
		(pad "2" smd circle
			(at 0.40005 0)
			(size 0 0)
			(layers "F.Cu" "F.Mask" "F.Paste")
			(net "GND")
		)
	)
	(footprint ""
		(layer "F.Cu")
		(at 372.937278 -145.536158 180)
		(property "Reference" "R8293"
			(at 0 0 180)
			(layer "F.SilkS")
			(hide yes)
			(effects
				(font
					(size 1.27 1.27)
				)
			)
		)
		(property "Value" ""
			(at 0 0 180)
			(layer "F.Fab")
			(effects
				(font
					(size 1.27 1.27)
				)
			)
		)
		(duplicate_pad_numbers_are_jumpers no)
		(fp_line
			(start 0.7874 0.4064)
			(end -0.7874 0.4064)
			(stroke
				(width 0.1524)
				(type default)
			)
			(layer "F.SilkS")
		)
		(fp_line
			(start 0.7874 -0.4064)
			(end 0.7874 0.4064)
			(stroke
				(width 0.1524)
				(type default)
			)
			(layer "F.SilkS")
		)
		(fp_line
			(start -0.7874 0.4064)
			(end -0.7874 -0.4064)
			(stroke
				(width 0.1524)
				(type default)
			)
			(layer "F.SilkS")
		)
		(fp_line
			(start -0.7874 -0.4064)
			(end 0.7874 -0.4064)
			(stroke
				(width 0.1524)
				(type default)
			)
			(layer "F.SilkS")
		)
		(fp_line
			(start 0.67945 0.3048)
			(end 0.120396 0.3048)
			(stroke
				(width 0.1)
				(type default)
			)
			(layer "F.Fab")
		)
		(fp_line
			(start 0.67945 -0.3048)
			(end 0.67945 0.3048)
			(stroke
				(width 0.1)
				(type default)
			)
			(layer "F.Fab")
		)
		(fp_line
			(start 0.12065 -0.2794)
			(end 0.12065 -0.3048)
			(stroke
				(width 0.1)
				(type default)
			)
			(layer "F.Fab")
		)
		(fp_line
			(start 0.12065 -0.3048)
			(end 0.67945 -0.3048)
			(stroke
				(width 0.1)
				(type default)
			)
			(layer "F.Fab")
		)
		(fp_line
			(start 0.120396 0.3048)
			(end 0.120396 0.2794)
			(stroke
				(width 0.1)
				(type default)
			)
			(layer "F.Fab")
		)
		(fp_line
			(start 0.120396 0.2794)
			(end -0.12065 0.2794)
			(stroke
				(width 0.1)
				(type default)
			)
			(layer "F.Fab")
		)
		(fp_line
			(start -0.12065 0.3048)
			(end -0.67945 0.3048)
			(stroke
				(width 0.1)
				(type default)
			)
			(layer "F.Fab")
		)
		(fp_line
			(start -0.12065 0.2794)
			(end -0.12065 0.3048)
			(stroke
				(width 0.1)
				(type default)
			)
			(layer "F.Fab")
		)
		(fp_line
			(start -0.12065 -0.2794)
			(end 0.12065 -0.2794)
			(stroke
				(width 0.1)
				(type default)
			)
			(layer "F.Fab")
		)
		(fp_line
			(start -0.12065 -0.305054)
			(end -0.12065 -0.2794)
			(stroke
				(width 0.1)
				(type default)
			)
			(layer "F.Fab")
		)
		(fp_line
			(start -0.67945 0.3048)
			(end -0.67945 -0.305054)
			(stroke
				(width 0.1)
				(type default)
			)
			(layer "F.Fab")
		)
		(fp_line
			(start -0.67945 -0.305054)
			(end -0.12065 -0.305054)
			(stroke
				(width 0.1)
				(type default)
			)
			(layer "F.Fab")
		)
		(pad "1" smd circle
			(at -0.40005 0 180)
			(size 0 0)
			(layers "F.Cu" "F.Mask" "F.Paste")
			(net "PVDD18_S5_P0")
		)
		(pad "2" smd circle
			(at 0.40005 0 180)
			(size 0 0)
			(layers "F.Cu" "F.Mask" "F.Paste")
			(net "SVID_PVDDCR_CPU0_P0_SVC_R")
		)
	)
	(footprint ""
		(layer "F.Cu")
		(at 214.86241 -26.111454 90)
		(property "Reference" "OSC1"
			(at 2.590546 -0.070612 0)
			(unlocked yes)
			(layer "F.SilkS")
			(effects
				(font
					(size 0.7874 0.5842)
					(thickness 0.1524)
				)
				(justify left)
			)
		)
		(property "Value" ""
			(at 0 0 90)
			(layer "F.Fab")
			(effects
				(font
					(size 1.27 1.27)
				)
			)
		)
		(duplicate_pad_numbers_are_jumpers no)
		(fp_line
			(start 1.546098 -1.94945)
			(end -1.546098 -1.94945)
			(stroke
				(width 0.1524)
				(type default)
			)
			(layer "F.SilkS")
		)
		(fp_line
			(start -1.546098 -1.94945)
			(end -1.546098 1.94945)
			(stroke
				(width 0.1524)
				(type default)
			)
			(layer "F.SilkS")
		)
		(fp_line
			(start 1.546098 1.94945)
			(end 1.546098 -1.94945)
			(stroke
				(width 0.1524)
				(type default)
			)
			(layer "F.SilkS")
		)
		(fp_line
			(start -1.546098 1.94945)
			(end 1.546098 1.94945)
			(stroke
				(width 0.1524)
				(type default)
			)
			(layer "F.SilkS")
		)
		(fp_poly
			(pts
				(xy -1.085596 -2.087372) (xy -0.450596 -3.408172) (xy -1.568196 -3.408172)
			)
			(stroke
				(width 0)
				(type default)
			)
			(fill yes)
			(layer "F.SilkS")
		)
		(fp_line
			(start 1.299972 -1.649984)
			(end 1.299972 1.649984)
			(stroke
				(width 0.1)
				(type default)
			)
			(layer "F.Fab")
		)
		(fp_line
			(start -1.299972 -1.649984)
			(end 1.299972 -1.649984)
			(stroke
				(width 0.1)
				(type default)
			)
			(layer "F.Fab")
		)
		(fp_line
			(start 1.299972 1.649984)
			(end -1.299972 1.649984)
			(stroke
				(width 0.1)
				(type default)
			)
			(layer "F.Fab")
		)
		(fp_line
			(start -1.299972 1.649984)
			(end -1.299972 -1.649984)
			(stroke
				(width 0.1)
				(type default)
			)
			(layer "F.Fab")
		)
		(fp_poly
			(pts
				(xy -1.768094 -1.059942) (xy -3.088894 -1.694942) (xy -3.088894 -0.577342)
			)
			(stroke
				(width 0)
				(type default)
			)
			(fill yes)
			(layer "F.Fab")
		)
		(pad "1" smd rect
			(at -0.8001 -1.059942 90)
			(size 1.2192 1.4986)
			(layers "F.Cu" "F.Mask" "F.Paste")
			(net "CLK_50M_EN")
		)
		(pad "2" smd rect
			(at -0.8001 1.059942 270)
			(size 1.2192 1.4986)
			(layers "F.Cu" "F.Mask" "F.Paste")
			(net "GND")
		)
		(pad "3" smd rect
			(at 0.8001 1.059942 90)
			(size 1.2192 1.4986)
			(layers "F.Cu" "F.Mask" "F.Paste")
			(net "CLK_50M_RMII")
		)
		(pad "4" smd rect
			(at 0.8001 -1.059942 90)
			(size 1.2192 1.4986)
			(layers "F.Cu" "F.Mask" "F.Paste")
			(net "P3V3_AUX")
		)
	)
	(footprint ""
		(layer "F.Cu")
		(at 430.2379 -400.987768 -90)
		(property "Reference" "R1055"
			(at 0 0 270)
			(layer "F.SilkS")
			(hide yes)
			(effects
				(font
					(size 1.27 1.27)
				)
			)
		)
		(property "Value" ""
			(at 0 0 270)
			(layer "F.Fab")
			(effects
				(font
					(size 1.27 1.27)
				)
			)
		)
		(duplicate_pad_numbers_are_jumpers no)
		(fp_line
			(start -0.32512 0.175006)
			(end -0.32512 -0.175006)
			(stroke
				(width 0.1)
				(type default)
			)
			(layer "F.Fab")
		)
		(fp_line
			(start 0.32512 0.175006)
			(end -0.32512 0.175006)
			(stroke
				(width 0.1)
				(type default)
			)
			(layer "F.Fab")
		)
		(fp_line
			(start -0.32512 -0.175006)
			(end 0.32512 -0.175006)
			(stroke
				(width 0.1)
				(type default)
			)
			(layer "F.Fab")
		)
		(fp_line
			(start 0.32512 -0.175006)
			(end 0.32512 0.175006)
			(stroke
				(width 0.1)
				(type default)
			)
			(layer "F.Fab")
		)
		(pad "1" smd rect
			(at -0.2667 0 270)
			(size 0.3048 0.381)
			(layers "F.Cu" "F.Mask" "F.Paste")
			(net "P1V8_CPU0_RT_1D")
		)
		(pad "2" smd rect
			(at 0.2667 0 90)
			(size 0.3048 0.381)
			(layers "F.Cu" "F.Mask" "F.Paste")
			(net "RT_CPU0_P2_ADDR3")
		)
	)
)
